# T6G (Grand Teton) — schematic netlist excerpt (pin names and nets, part order shuffled) for the footprints in the layout excerpt that follows; sources: Cadence DE-HDL packaged netlist, KiCad conversion of 04192023_DAF0TMB3IC0_F0TG_MB_C_brd_V02_OCP.brd

PC291_4  Q_CAP  1UF 25V 10% X6S  pkg C0402  page 212 : A = SW_P12V_AUX_PVDDCR_CPU0_P1_FLT ; B = GND
PC438_1  Q_CAP  0.1UF 25V 10% X7R  pkg 0402  page 222 : A = SW_P12V_AUX_PVDDIO_P1_FLT ; B = GND

(kicad_pcb
	(version 20260206)
	(generator "pcbnew")
	(generator_version "10.0")
	(general
		(thickness 1.6)
		(legacy_teardrops no)
	)
	(paper "A4")
	(title_block
		(title "04192023_DAF0TMB3IC0_F0TG_MB_C_brd_V02_OCP.brd")
		(comment 1 "Grand Teton / footprints 3105-3106 of 8354")
	)
	(layers
		(0 "F.Cu" signal "TOP")
		(4 "In1.Cu" signal "GND")
		(6 "In2.Cu" signal "IN1")
		(8 "In3.Cu" signal "GND1")
		(10 "In4.Cu" signal "IN2")
		(12 "In5.Cu" signal "GND2")
		(14 "In6.Cu" signal "IN3")
		(16 "In7.Cu" signal "GND3")
		(18 "In8.Cu" signal "VCC")
		(20 "In9.Cu" signal "VCC1")
		(22 "In10.Cu" signal "GND4")
		(24 "In11.Cu" signal "IN4")
		(26 "In12.Cu" signal "GND5")
		(28 "In13.Cu" signal "IN5")
		(30 "In14.Cu" signal "GND6")
		(32 "In15.Cu" signal "IN6")
		(34 "In16.Cu" signal "GND7")
		(2 "B.Cu" signal "BOTTOM")
		(9 "F.Adhes" user "F.Adhesive")
		(11 "B.Adhes" user "B.Adhesive")
		(13 "F.Paste" user "Package Geometry/Pastemask Top")
		(15 "B.Paste" user "Package Geometry/Pastemask Bottom")
		(5 "F.SilkS" user "Ref Des/Silkscreen Top")
		(7 "B.SilkS" user "Ref Des/Silkscreen Bottom")
		(1 "F.Mask" user "Board Geometry/Soldermask Top")
		(3 "B.Mask" user "Board Geometry/Soldermask Bottom")
		(17 "Dwgs.User" user "User.Drawings")
		(19 "Cmts.User" user "User.Comments")
		(21 "Eco1.User" user "User.Eco1")
		(23 "Eco2.User" user "User.Eco2")
		(25 "Edge.Cuts" user "Board Geometry/Outline")
		(27 "Margin" user)
		(31 "F.CrtYd" user "Package Geometry/Place Bound Top")
		(29 "B.CrtYd" user "Package Geometry/Place Bound Bottom")
		(35 "F.Fab" user "Ref Des/Assembly Top")
		(33 "B.Fab" user "Ref Des/Assembly Bottom")
	)
	(footprint ""
		(layer "F.Cu")
		(at 103.819706 -178.077876 90)
		(property "Reference" "PC291_4"
			(at 0 0 90)
			(layer "F.SilkS")
			(hide yes)
			(effects
				(font
					(size 1.27 1.27)
				)
			)
		)
		(property "Value" ""
			(at 0 0 90)
			(layer "F.Fab")
			(effects
				(font
					(size 1.27 1.27)
				)
			)
		)
		(duplicate_pad_numbers_are_jumpers no)
		(fp_line
			(start 0.7874 -0.4064)
			(end 0.7874 0.4064)
			(stroke
				(width 0.1524)
				(type default)
			)
			(layer "F.SilkS")
		)
		(fp_line
			(start -0.7874 -0.4064)
			(end 0.7874 -0.4064)
			(stroke
				(width 0.1524)
				(type default)
			)
			(layer "F.SilkS")
		)
		(fp_line
			(start 0.7874 0.4064)
			(end -0.7874 0.4064)
			(stroke
				(width 0.1524)
				(type default)
			)
			(layer "F.SilkS")
		)
		(fp_line
			(start -0.7874 0.4064)
			(end -0.7874 -0.4064)
			(stroke
				(width 0.1524)
				(type default)
			)
			(layer "F.SilkS")
		)
		(fp_line
			(start -0.12065 -0.305054)
			(end -0.12065 -0.2794)
			(stroke
				(width 0.1)
				(type default)
			)
			(layer "F.Fab")
		)
		(fp_line
			(start -0.67945 -0.305054)
			(end -0.12065 -0.305054)
			(stroke
				(width 0.1)
				(type default)
			)
			(layer "F.Fab")
		)
		(fp_line
			(start 0.67945 -0.3048)
			(end 0.67945 0.3048)
			(stroke
				(width 0.1)
				(type default)
			)
			(layer "F.Fab")
		)
		(fp_line
			(start 0.12065 -0.3048)
			(end 0.67945 -0.3048)
			(stroke
				(width 0.1)
				(type default)
			)
			(layer "F.Fab")
		)
		(fp_line
			(start 0.12065 -0.2794)
			(end 0.12065 -0.3048)
			(stroke
				(width 0.1)
				(type default)
			)
			(layer "F.Fab")
		)
		(fp_line
			(start -0.12065 -0.2794)
			(end 0.12065 -0.2794)
			(stroke
				(width 0.1)
				(type default)
			)
			(layer "F.Fab")
		)
		(fp_line
			(start 0.120396 0.2794)
			(end -0.12065 0.2794)
			(stroke
				(width 0.1)
				(type default)
			)
			(layer "F.Fab")
		)
		(fp_line
			(start -0.12065 0.2794)
			(end -0.12065 0.3048)
			(stroke
				(width 0.1)
				(type default)
			)
			(layer "F.Fab")
		)
		(fp_line
			(start 0.67945 0.3048)
			(end 0.120396 0.3048)
			(stroke
				(width 0.1)
				(type default)
			)
			(layer "F.Fab")
		)
		(fp_line
			(start 0.120396 0.3048)
			(end 0.120396 0.2794)
			(stroke
				(width 0.1)
				(type default)
			)
			(layer "F.Fab")
		)
		(fp_line
			(start -0.12065 0.3048)
			(end -0.67945 0.3048)
			(stroke
				(width 0.1)
				(type default)
			)
			(layer "F.Fab")
		)
		(fp_line
			(start -0.67945 0.3048)
			(end -0.67945 -0.305054)
			(stroke
				(width 0.1)
				(type default)
			)
			(layer "F.Fab")
		)
		(pad "1" smd circle
			(at -0.40005 0 90)
			(size 0 0)
			(layers "F.Cu" "F.Mask" "F.Paste")
			(net "SW_P12V_AUX_PVDDCR_CPU0_P1_FLT")
		)
		(pad "2" smd circle
			(at 0.40005 0 90)
			(size 0 0)
			(layers "F.Cu" "F.Mask" "F.Paste")
			(net "GND")
		)
	)
	(footprint ""
		(layer "F.Cu")
		(at 49.407318 -351.10547)
		(property "Reference" "PC438_1"
			(at 0 0 0)
			(layer "F.SilkS")
			(hide yes)
			(effects
				(font
					(size 1.27 1.27)
				)
			)
		)
		(property "Value" ""
			(at 0 0 0)
			(layer "F.Fab")
			(effects
				(font
					(size 1.27 1.27)
				)
			)
		)
		(duplicate_pad_numbers_are_jumpers no)
		(fp_line
			(start -0.7874 -0.4064)
			(end 0.7874 -0.4064)
			(stroke
				(width 0.1524)
				(type default)
			)
			(layer "F.SilkS")
		)
		(fp_line
			(start -0.7874 0.4064)
			(end -0.7874 -0.4064)
			(stroke
				(width 0.1524)
				(type default)
			)
			(layer "F.SilkS")
		)
		(fp_line
			(start 0.7874 -0.4064)
			(end 0.7874 0.4064)
			(stroke
				(width 0.1524)
				(type default)
			)
			(layer "F.SilkS")
		)
		(fp_line
			(start 0.7874 0.4064)
			(end -0.7874 0.4064)
			(stroke
				(width 0.1524)
				(type default)
			)
			(layer "F.SilkS")
		)
		(fp_line
			(start -0.67945 -0.305054)
			(end -0.12065 -0.305054)
			(stroke
				(width 0.1)
				(type default)
			)
			(layer "F.Fab")
		)
		(fp_line
			(start -0.67945 0.3048)
			(end -0.67945 -0.305054)
			(stroke
				(width 0.1)
				(type default)
			)
			(layer "F.Fab")
		)
		(fp_line
			(start -0.12065 -0.305054)
			(end -0.12065 -0.2794)
			(stroke
				(width 0.1)
				(type default)
			)
			(layer "F.Fab")
		)
		(fp_line
			(start -0.12065 -0.2794)
			(end 0.12065 -0.2794)
			(stroke
				(width 0.1)
				(type default)
			)
			(layer "F.Fab")
		)
		(fp_line
			(start -0.12065 0.2794)
			(end -0.12065 0.3048)
			(stroke
				(width 0.1)
				(type default)
			)
			(layer "F.Fab")
		)
		(fp_line
			(start -0.12065 0.3048)
			(end -0.67945 0.3048)
			(stroke
				(width 0.1)
				(type default)
			)
			(layer "F.Fab")
		)
		(fp_line
			(start 0.120396 0.2794)
			(end -0.12065 0.2794)
			(stroke
				(width 0.1)
				(type default)
			)
			(layer "F.Fab")
		)
		(fp_line
			(start 0.120396 0.3048)
			(end 0.120396 0.2794)
			(stroke
				(width 0.1)
				(type default)
			)
			(layer "F.Fab")
		)
		(fp_line
			(start 0.12065 -0.3048)
			(end 0.67945 -0.3048)
			(stroke
				(width 0.1)
				(type default)
			)
			(layer "F.Fab")
		)
		(fp_line
			(start 0.12065 -0.2794)
			(end 0.12065 -0.3048)
			(stroke
				(width 0.1)
				(type default)
			)
			(layer "F.Fab")
		)
		(fp_line
			(start 0.67945 -0.3048)
			(end 0.67945 0.3048)
			(stroke
				(width 0.1)
				(type default)
			)
			(layer "F.Fab")
		)
		(fp_line
			(start 0.67945 0.3048)
			(end 0.120396 0.3048)
			(stroke
				(width 0.1)
				(type default)
			)
			(layer "F.Fab")
		)
		(pad "1" smd circle
			(at -0.40005 0)
			(size 0 0)
			(layers "F.Cu" "F.Mask" "F.Paste")
			(net "SW_P12V_AUX_PVDDIO_P1_FLT")
		)
		(pad "2" smd circle
			(at 0.40005 0)
			(size 0 0)
			(layers "F.Cu" "F.Mask" "F.Paste")
			(net "GND")
		)
	)
)
